(kicad_pcb
	(version 20260206)
	(generator "pcbnew")
	(generator_version "10.0")
	(general
		(thickness 1.6)
		(legacy_teardrops no)
	)
	(paper "A4")
	(title_block
		(title "04192023_DAF0TMB3IC0_F0TG_MB_C_brd_V02_OCP.brd")
		(comment 1 "Grand Teton / footprints 4923-4929 of 8354")
	)
	(layers
		(0 "F.Cu" signal "TOP")
		(4 "In1.Cu" signal "GND")
		(6 "In2.Cu" signal "IN1")
		(8 "In3.Cu" signal "GND1")
		(10 "In4.Cu" signal "IN2")
		(12 "In5.Cu" signal "GND2")
		(14 "In6.Cu" signal "IN3")
		(16 "In7.Cu" signal "GND3")
		(18 "In8.Cu" signal "VCC")
		(20 "In9.Cu" signal "VCC1")
		(22 "In10.Cu" signal "GND4")
		(24 "In11.Cu" signal "IN4")
		(26 "In12.Cu" signal "GND5")
		(28 "In13.Cu" signal "IN5")
		(30 "In14.Cu" signal "GND6")
		(32 "In15.Cu" signal "IN6")
		(34 "In16.Cu" signal "GND7")
		(2 "B.Cu" signal "BOTTOM")
		(9 "F.Adhes" user "F.Adhesive")
		(11 "B.Adhes" user "B.Adhesive")
		(13 "F.Paste" user "Package Geometry/Pastemask Top")
		(15 "B.Paste" user "Package Geometry/Pastemask Bottom")
		(5 "F.SilkS" user "Ref Des/Silkscreen Top")
		(7 "B.SilkS" user "Ref Des/Silkscreen Bottom")
		(1 "F.Mask" user "Board Geometry/Soldermask Top")
		(3 "B.Mask" user "Board Geometry/Soldermask Bottom")
		(17 "Dwgs.User" user "User.Drawings")
		(19 "Cmts.User" user "User.Comments")
		(21 "Eco1.User" user "User.Eco1")
		(23 "Eco2.User" user "User.Eco2")
		(25 "Edge.Cuts" user "Board Geometry/Outline")
		(27 "Margin" user)
		(31 "F.CrtYd" user "Package Geometry/Place Bound Top")
		(29 "B.CrtYd" user "Package Geometry/Place Bound Bottom")
		(35 "F.Fab" user "Ref Des/Assembly Top")
		(33 "B.Fab" user "Ref Des/Assembly Bottom")
	)
	(footprint ""
		(layer "F.Cu")
		(at 195.888864 -351.409254 -90)
		(property "Reference" "PC510_2"
			(at 0 0 270)
			(layer "F.SilkS")
			(hide yes)
			(effects
				(font
					(size 1.27 1.27)
				)
			)
		)
		(property "Value" ""
			(at 0 0 270)
			(layer "F.Fab")
			(effects
				(font
					(size 1.27 1.27)
				)
			)
		)
		(duplicate_pad_numbers_are_jumpers no)
		(fp_line
			(start -0.7874 0.4064)
			(end -0.7874 -0.4064)
			(stroke
				(width 0.1524)
				(type default)
			)
			(layer "F.SilkS")
		)
		(fp_line
			(start 0.7874 0.4064)
			(end -0.7874 0.4064)
			(stroke
				(width 0.1524)
				(type default)
			)
			(layer "F.SilkS")
		)
		(fp_line
			(start -0.7874 -0.4064)
			(end 0.7874 -0.4064)
			(stroke
				(width 0.1524)
				(type default)
			)
			(layer "F.SilkS")
		)
		(fp_line
			(start 0.7874 -0.4064)
			(end 0.7874 0.4064)
			(stroke
				(width 0.1524)
				(type default)
			)
			(layer "F.SilkS")
		)
		(fp_line
			(start -0.67945 0.3048)
			(end -0.67945 -0.305054)
			(stroke
				(width 0.1)
				(type default)
			)
			(layer "F.Fab")
		)
		(fp_line
			(start -0.12065 0.3048)
			(end -0.67945 0.3048)
			(stroke
				(width 0.1)
				(type default)
			)
			(layer "F.Fab")
		)
		(fp_line
			(start 0.120396 0.3048)
			(end 0.120396 0.2794)
			(stroke
				(width 0.1)
				(type default)
			)
			(layer "F.Fab")
		)
		(fp_line
			(start 0.67945 0.3048)
			(end 0.120396 0.3048)
			(stroke
				(width 0.1)
				(type default)
			)
			(layer "F.Fab")
		)
		(fp_line
			(start -0.12065 0.2794)
			(end -0.12065 0.3048)
			(stroke
				(width 0.1)
				(type default)
			)
			(layer "F.Fab")
		)
		(fp_line
			(start 0.120396 0.2794)
			(end -0.12065 0.2794)
			(stroke
				(width 0.1)
				(type default)
			)
			(layer "F.Fab")
		)
		(fp_line
			(start -0.12065 -0.2794)
			(end 0.12065 -0.2794)
			(stroke
				(width 0.1)
				(type default)
			)
			(layer "F.Fab")
		)
		(fp_line
			(start 0.12065 -0.2794)
			(end 0.12065 -0.3048)
			(stroke
				(width 0.1)
				(type default)
			)
			(layer "F.Fab")
		)
		(fp_line
			(start 0.12065 -0.3048)
			(end 0.67945 -0.3048)
			(stroke
				(width 0.1)
				(type default)
			)
			(layer "F.Fab")
		)
		(fp_line
			(start 0.67945 -0.3048)
			(end 0.67945 0.3048)
			(stroke
				(width 0.1)
				(type default)
			)
			(layer "F.Fab")
		)
		(fp_line
			(start -0.67945 -0.305054)
			(end -0.12065 -0.305054)
			(stroke
				(width 0.1)
				(type default)
			)
			(layer "F.Fab")
		)
		(fp_line
			(start -0.12065 -0.305054)
			(end -0.12065 -0.2794)
			(stroke
				(width 0.1)
				(type default)
			)
			(layer "F.Fab")
		)
		(pad "1" smd circle
			(at -0.40005 0 270)
			(size 0 0)
			(layers "F.Cu" "F.Mask" "F.Paste")
			(net "SW_P12V_AUX_PVDD11_S3_P1_FLT")
		)
		(pad "2" smd circle
			(at 0.40005 0 270)
			(size 0 0)
			(layers "F.Cu" "F.Mask" "F.Paste")
			(net "GND")
		)
	)
	(footprint ""
		(layer "F.Cu")
		(at 320.571876 -70.098412 90)
		(property "Reference" "D96"
			(at -3.934714 -0.691642 90)
			(unlocked yes)
			(layer "F.SilkS")
			(effects
				(font
					(size 0.7874 0.5842)
					(thickness 0.1524)
				)
				(justify left)
			)
		)
		(property "Value" ""
			(at 0 0 90)
			(layer "F.Fab")
			(effects
				(font
					(size 1.27 1.27)
				)
			)
		)
		(duplicate_pad_numbers_are_jumpers no)
		(fp_line
			(start 1.16078 -0.4826)
			(end 1.16078 0.4826)
			(stroke
				(width 0.1524)
				(type default)
			)
			(layer "F.SilkS")
		)
		(fp_line
			(start 1.03378 -0.4826)
			(end 1.03378 0.4826)
			(stroke
				(width 0.1524)
				(type default)
			)
			(layer "F.SilkS")
		)
		(fp_line
			(start 0.90678 -0.4826)
			(end 0.90678 0.4826)
			(stroke
				(width 0.1524)
				(type default)
			)
			(layer "F.SilkS")
		)
		(fp_line
			(start -0.64008 -0.4826)
			(end 1.16078 -0.4826)
			(stroke
				(width 0.1524)
				(type default)
			)
			(layer "F.SilkS")
		)
		(fp_line
			(start -0.79248 -0.4826)
			(end 1.03378 -0.4826)
			(stroke
				(width 0.1524)
				(type default)
			)
			(layer "F.SilkS")
		)
		(fp_line
			(start -0.89408 -0.4826)
			(end 0.90678 -0.4826)
			(stroke
				(width 0.1524)
				(type default)
			)
			(layer "F.SilkS")
		)
		(fp_line
			(start 1.16078 0.4826)
			(end -0.64008 0.4826)
			(stroke
				(width 0.1524)
				(type default)
			)
			(layer "F.SilkS")
		)
		(fp_line
			(start 1.03378 0.4826)
			(end -0.79248 0.4826)
			(stroke
				(width 0.1524)
				(type default)
			)
			(layer "F.SilkS")
		)
		(fp_line
			(start 0.90678 0.4826)
			(end -0.90678 0.4826)
			(stroke
				(width 0.1524)
				(type default)
			)
			(layer "F.SilkS")
		)
		(fp_line
			(start -0.90678 0.4826)
			(end -0.90678 -0.4699)
			(stroke
				(width 0.1524)
				(type default)
			)
			(layer "F.SilkS")
		)
		(fp_line
			(start 0.499872 -0.249936)
			(end 0.499872 0.249936)
			(stroke
				(width 0.1)
				(type default)
			)
			(layer "F.Fab")
		)
		(fp_line
			(start -0.499872 -0.249936)
			(end 0.499872 -0.249936)
			(stroke
				(width 0.1)
				(type default)
			)
			(layer "F.Fab")
		)
		(fp_line
			(start 0.499872 0.249936)
			(end -0.499872 0.249936)
			(stroke
				(width 0.1)
				(type default)
			)
			(layer "F.Fab")
		)
		(fp_line
			(start -0.499872 0.249936)
			(end -0.499872 -0.249936)
			(stroke
				(width 0.1)
				(type default)
			)
			(layer "F.Fab")
		)
		(pad "A" smd rect
			(at -0.47498 0 90)
			(size 0.6096 0.7112)
			(layers "F.Cu" "F.Mask" "F.Paste")
			(net "LED_PWRGD_PS_PWROK_PLD")
		)
		(pad "C" smd rect
			(at 0.47498 0 90)
			(size 0.6096 0.7112)
			(layers "F.Cu" "F.Mask" "F.Paste")
			(net "LED_PWRGD_PS_PWROK_PLD_D")
		)
	)
	(footprint ""
		(layer "F.Cu")
		(at 170.970702 -439.740294 90)
		(property "Reference" "R2835"
			(at 0 0 90)
			(layer "F.SilkS")
			(hide yes)
			(effects
				(font
					(size 1.27 1.27)
				)
			)
		)
		(property "Value" ""
			(at 0 0 90)
			(layer "F.Fab")
			(effects
				(font
					(size 1.27 1.27)
				)
			)
		)
		(duplicate_pad_numbers_are_jumpers no)
		(fp_line
			(start 0.7874 -0.4064)
			(end 0.7874 0.4064)
			(stroke
				(width 0.1524)
				(type default)
			)
			(layer "F.SilkS")
		)
		(fp_line
			(start -0.7874 -0.4064)
			(end 0.7874 -0.4064)
			(stroke
				(width 0.1524)
				(type default)
			)
			(layer "F.SilkS")
		)
		(fp_line
			(start 0.7874 0.4064)
			(end -0.7874 0.4064)
			(stroke
				(width 0.1524)
				(type default)
			)
			(layer "F.SilkS")
		)
		(fp_line
			(start -0.7874 0.4064)
			(end -0.7874 -0.4064)
			(stroke
				(width 0.1524)
				(type default)
			)
			(layer "F.SilkS")
		)
		(fp_line
			(start -0.12065 -0.305054)
			(end -0.12065 -0.2794)
			(stroke
				(width 0.1)
				(type default)
			)
			(layer "F.Fab")
		)
		(fp_line
			(start -0.67945 -0.305054)
			(end -0.12065 -0.305054)
			(stroke
				(width 0.1)
				(type default)
			)
			(layer "F.Fab")
		)
		(fp_line
			(start 0.67945 -0.3048)
			(end 0.67945 0.3048)
			(stroke
				(width 0.1)
				(type default)
			)
			(layer "F.Fab")
		)
		(fp_line
			(start 0.12065 -0.3048)
			(end 0.67945 -0.3048)
			(stroke
				(width 0.1)
				(type default)
			)
			(layer "F.Fab")
		)
		(fp_line
			(start 0.12065 -0.2794)
			(end 0.12065 -0.3048)
			(stroke
				(width 0.1)
				(type default)
			)
			(layer "F.Fab")
		)
		(fp_line
			(start -0.12065 -0.2794)
			(end 0.12065 -0.2794)
			(stroke
				(width 0.1)
				(type default)
			)
			(layer "F.Fab")
		)
		(fp_line
			(start 0.120396 0.2794)
			(end -0.12065 0.2794)
			(stroke
				(width 0.1)
				(type default)
			)
			(layer "F.Fab")
		)
		(fp_line
			(start -0.12065 0.2794)
			(end -0.12065 0.3048)
			(stroke
				(width 0.1)
				(type default)
			)
			(layer "F.Fab")
		)
		(fp_line
			(start 0.67945 0.3048)
			(end 0.120396 0.3048)
			(stroke
				(width 0.1)
				(type default)
			)
			(layer "F.Fab")
		)
		(fp_line
			(start 0.120396 0.3048)
			(end 0.120396 0.2794)
			(stroke
				(width 0.1)
				(type default)
			)
			(layer "F.Fab")
		)
		(fp_line
			(start -0.12065 0.3048)
			(end -0.67945 0.3048)
			(stroke
				(width 0.1)
				(type default)
			)
			(layer "F.Fab")
		)
		(fp_line
			(start -0.67945 0.3048)
			(end -0.67945 -0.305054)
			(stroke
				(width 0.1)
				(type default)
			)
			(layer "F.Fab")
		)
		(pad "1" smd circle
			(at -0.40005 0 90)
			(size 0 0)
			(layers "F.Cu" "F.Mask" "F.Paste")
			(net "P3V3_AUX")
		)
		(pad "2" smd circle
			(at 0.40005 0 90)
			(size 0 0)
			(layers "F.Cu" "F.Mask" "F.Paste")
			(net "BIC_MONITER_N")
		)
	)
	(footprint ""
		(layer "F.Cu")
		(at 158.668466 -408.517344 -90)
		(property "Reference" "C6721"
			(at 0 0 270)
			(layer "F.SilkS")
			(hide yes)
			(effects
				(font
					(size 1.27 1.27)
				)
			)
		)
		(property "Value" ""
			(at 0 0 270)
			(layer "F.Fab")
			(effects
				(font
					(size 1.27 1.27)
				)
			)
		)
		(duplicate_pad_numbers_are_jumpers no)
		(fp_line
			(start -0.299974 0.150114)
			(end -0.299974 -0.150114)
			(stroke
				(width 0.1)
				(type default)
			)
			(layer "F.Fab")
		)
		(fp_line
			(start 0.299974 0.150114)
			(end -0.299974 0.150114)
			(stroke
				(width 0.1)
				(type default)
			)
			(layer "F.Fab")
		)
		(fp_line
			(start -0.299974 -0.150114)
			(end 0.299974 -0.150114)
			(stroke
				(width 0.1)
				(type default)
			)
			(layer "F.Fab")
		)
		(fp_line
			(start 0.299974 -0.150114)
			(end 0.299974 0.150114)
			(stroke
				(width 0.1)
				(type default)
			)
			(layer "F.Fab")
		)
		(pad "1" smd rect
			(at -0.2667 0 270)
			(size 0.3048 0.381)
			(layers "F.Cu" "F.Mask" "F.Paste")
			(net "P5E_CPU1_P2_TX_BUF_C_DP<14>")
		)
		(pad "2" smd rect
			(at 0.2667 0 270)
			(size 0.3048 0.381)
			(layers "F.Cu" "F.Mask" "F.Paste")
			(net "P5E_CPU1_P2_TX_BUF_DP<14>")
		)
	)
	(footprint ""
		(layer "F.Cu")
		(at 392.593576 -394.82268 90)
		(property "Reference" "C993"
			(at 0 0 90)
			(layer "F.SilkS")
			(hide yes)
			(effects
				(font
					(size 1.27 1.27)
				)
			)
		)
		(property "Value" ""
			(at 0 0 90)
			(layer "F.Fab")
			(effects
				(font
					(size 1.27 1.27)
				)
			)
		)
		(duplicate_pad_numbers_are_jumpers no)
		(fp_line
			(start 0.7874 -0.4064)
			(end 0.7874 0.4064)
			(stroke
				(width 0.1524)
				(type default)
			)
			(layer "F.SilkS")
		)
		(fp_line
			(start -0.7874 -0.4064)
			(end 0.7874 -0.4064)
			(stroke
				(width 0.1524)
				(type default)
			)
			(layer "F.SilkS")
		)
		(fp_line
			(start 0.7874 0.4064)
			(end -0.7874 0.4064)
			(stroke
				(width 0.1524)
				(type default)
			)
			(layer "F.SilkS")
		)
		(fp_line
			(start -0.7874 0.4064)
			(end -0.7874 -0.4064)
			(stroke
				(width 0.1524)
				(type default)
			)
			(layer "F.SilkS")
		)
		(fp_line
			(start -0.12065 -0.305054)
			(end -0.12065 -0.2794)
			(stroke
				(width 0.1)
				(type default)
			)
			(layer "F.Fab")
		)
		(fp_line
			(start -0.67945 -0.305054)
			(end -0.12065 -0.305054)
			(stroke
				(width 0.1)
				(type default)
			)
			(layer "F.Fab")
		)
		(fp_line
			(start 0.67945 -0.3048)
			(end 0.67945 0.3048)
			(stroke
				(width 0.1)
				(type default)
			)
			(layer "F.Fab")
		)
		(fp_line
			(start 0.12065 -0.3048)
			(end 0.67945 -0.3048)
			(stroke
				(width 0.1)
				(type default)
			)
			(layer "F.Fab")
		)
		(fp_line
			(start 0.12065 -0.2794)
			(end 0.12065 -0.3048)
			(stroke
				(width 0.1)
				(type default)
			)
			(layer "F.Fab")
		)
		(fp_line
			(start -0.12065 -0.2794)
			(end 0.12065 -0.2794)
			(stroke
				(width 0.1)
				(type default)
			)
			(layer "F.Fab")
		)
		(fp_line
			(start 0.120396 0.2794)
			(end -0.12065 0.2794)
			(stroke
				(width 0.1)
				(type default)
			)
			(layer "F.Fab")
		)
		(fp_line
			(start -0.12065 0.2794)
			(end -0.12065 0.3048)
			(stroke
				(width 0.1)
				(type default)
			)
			(layer "F.Fab")
		)
		(fp_line
			(start 0.67945 0.3048)
			(end 0.120396 0.3048)
			(stroke
				(width 0.1)
				(type default)
			)
			(layer "F.Fab")
		)
		(fp_line
			(start 0.120396 0.3048)
			(end 0.120396 0.2794)
			(stroke
				(width 0.1)
				(type default)
			)
			(layer "F.Fab")
		)
		(fp_line
			(start -0.12065 0.3048)
			(end -0.67945 0.3048)
			(stroke
				(width 0.1)
				(type default)
			)
			(layer "F.Fab")
		)
		(fp_line
			(start -0.67945 0.3048)
			(end -0.67945 -0.305054)
			(stroke
				(width 0.1)
				(type default)
			)
			(layer "F.Fab")
		)
		(pad "1" smd circle
			(at -0.40005 0 90)
			(size 0 0)
			(layers "F.Cu" "F.Mask" "F.Paste")
			(net "P1V8_CPU0_RT3_1A")
		)
		(pad "2" smd circle
			(at 0.40005 0 90)
			(size 0 0)
			(layers "F.Cu" "F.Mask" "F.Paste")
			(net "GND")
		)
	)
	(footprint ""
		(layer "F.Cu")
		(at 91.759532 -332.02499 180)
		(property "Reference" "PC207"
			(at 0 0 180)
			(layer "F.SilkS")
			(hide yes)
			(effects
				(font
					(size 1.27 1.27)
				)
			)
		)
		(property "Value" ""
			(at 0 0 180)
			(layer "F.Fab")
			(effects
				(font
					(size 1.27 1.27)
				)
			)
		)
		(duplicate_pad_numbers_are_jumpers no)
		(fp_line
			(start 0.7874 0.4064)
			(end -0.7874 0.4064)
			(stroke
				(width 0.1524)
				(type default)
			)
			(layer "F.SilkS")
		)
		(fp_line
			(start 0.7874 -0.4064)
			(end 0.7874 0.4064)
			(stroke
				(width 0.1524)
				(type default)
			)
			(layer "F.SilkS")
		)
		(fp_line
			(start -0.7874 0.4064)
			(end -0.7874 -0.4064)
			(stroke
				(width 0.1524)
				(type default)
			)
			(layer "F.SilkS")
		)
		(fp_line
			(start -0.7874 -0.4064)
			(end 0.7874 -0.4064)
			(stroke
				(width 0.1524)
				(type default)
			)
			(layer "F.SilkS")
		)
		(fp_line
			(start 0.67945 0.3048)
			(end 0.120396 0.3048)
			(stroke
				(width 0.1)
				(type default)
			)
			(layer "F.Fab")
		)
		(fp_line
			(start 0.67945 -0.3048)
			(end 0.67945 0.3048)
			(stroke
				(width 0.1)
				(type default)
			)
			(layer "F.Fab")
		)
		(fp_line
			(start 0.12065 -0.2794)
			(end 0.12065 -0.3048)
			(stroke
				(width 0.1)
				(type default)
			)
			(layer "F.Fab")
		)
		(fp_line
			(start 0.12065 -0.3048)
			(end 0.67945 -0.3048)
			(stroke
				(width 0.1)
				(type default)
			)
			(layer "F.Fab")
		)
		(fp_line
			(start 0.120396 0.3048)
			(end 0.120396 0.2794)
			(stroke
				(width 0.1)
				(type default)
			)
			(layer "F.Fab")
		)
		(fp_line
			(start 0.120396 0.2794)
			(end -0.12065 0.2794)
			(stroke
				(width 0.1)
				(type default)
			)
			(layer "F.Fab")
		)
		(fp_line
			(start -0.12065 0.3048)
			(end -0.67945 0.3048)
			(stroke
				(width 0.1)
				(type default)
			)
			(layer "F.Fab")
		)
		(fp_line
			(start -0.12065 0.2794)
			(end -0.12065 0.3048)
			(stroke
				(width 0.1)
				(type default)
			)
			(layer "F.Fab")
		)
		(fp_line
			(start -0.12065 -0.2794)
			(end 0.12065 -0.2794)
			(stroke
				(width 0.1)
				(type default)
			)
			(layer "F.Fab")
		)
		(fp_line
			(start -0.12065 -0.305054)
			(end -0.12065 -0.2794)
			(stroke
				(width 0.1)
				(type default)
			)
			(layer "F.Fab")
		)
		(fp_line
			(start -0.67945 0.3048)
			(end -0.67945 -0.305054)
			(stroke
				(width 0.1)
				(type default)
			)
			(layer "F.Fab")
		)
		(fp_line
			(start -0.67945 -0.305054)
			(end -0.12065 -0.305054)
			(stroke
				(width 0.1)
				(type default)
			)
			(layer "F.Fab")
		)
		(pad "1" smd circle
			(at -0.40005 0 180)
			(size 0 0)
			(layers "F.Cu" "F.Mask" "F.Paste")
			(net "SW_PVDDCR_CPU1_P1_SW5")
		)
		(pad "2" smd circle
			(at 0.40005 0 180)
			(size 0 0)
			(layers "F.Cu" "F.Mask" "F.Paste")
			(net "SW_PVDDCR_CPU1_P1_SW5_RC")
		)
	)
	(footprint ""
		(layer "F.Cu")
		(at 383.121662 -416.899344 -90)
		(property "Reference" "C6574"
			(at 0 0 270)
			(layer "F.SilkS")
			(hide yes)
			(effects
				(font
					(size 1.27 1.27)
				)
			)
		)
		(property "Value" ""
			(at 0 0 270)
			(layer "F.Fab")
			(effects
				(font
					(size 1.27 1.27)
				)
			)
		)
		(duplicate_pad_numbers_are_jumpers no)
		(fp_line
			(start -0.299974 0.150114)
			(end -0.299974 -0.150114)
			(stroke
				(width 0.1)
				(type default)
			)
			(layer "F.Fab")
		)
		(fp_line
			(start 0.299974 0.150114)
			(end -0.299974 0.150114)
			(stroke
				(width 0.1)
				(type default)
			)
			(layer "F.Fab")
		)
		(fp_line
			(start -0.299974 -0.150114)
			(end 0.299974 -0.150114)
			(stroke
				(width 0.1)
				(type default)
			)
			(layer "F.Fab")
		)
		(fp_line
			(start 0.299974 -0.150114)
			(end 0.299974 0.150114)
			(stroke
				(width 0.1)
				(type default)
			)
			(layer "F.Fab")
		)
		(pad "1" smd rect
			(at -0.2667 0 270)
			(size 0.3048 0.381)
			(layers "F.Cu" "F.Mask" "F.Paste")
			(net "P5E_CPU0_P2_TX_BUF_C_DN<4>")
		)
		(pad "2" smd rect
			(at 0.2667 0 270)
			(size 0.3048 0.381)
			(layers "F.Cu" "F.Mask" "F.Paste")
			(net "P5E_CPU0_P2_TX_BUF_DN<4>")
		)
	)
)
